# BASEBOARD_FAB2 (Tioga Pass) — schematic netlist excerpt (pin names and nets, part order shuffled) for the footprints in the layout excerpt that follows; sources: Cadence DE-HDL packaged netlist, KiCad conversion of Wiwynn_Tioga_Pass_MB.brd

R8C11  RES  20.0 1% CHIP  pkg 0402  page 138 : A = SMB_SMLINK0_STBY_LVC3_SDA_R1 ; B = SMB_SMLINK0_STBY_LVC3_SDA
R6W19  RES  0.0 5% CHIP  pkg 0402  page 155 : A = SPA_5V_SIN_SW_D ; B = SPA_SIN_SW_R
C6B6  CAP  0.22UF 16V 10% X7R  pkg 0402  page 105 : A = P3E_CPU0_PE1_PCH_TXN<14> ; B = P3E_CPU0_PE1_PCH_C_TXN<14>

(kicad_pcb
	(version 20260206)
	(generator "pcbnew")
	(generator_version "10.0")
	(general
		(thickness 1.6)
		(legacy_teardrops no)
	)
	(paper "A4")
	(title_block
		(title "Wiwynn_Tioga_Pass_MB.brd")
		(comment 1 "Tioga Pass / footprints 810-812 of 4770")
	)
	(layers
		(0 "F.Cu" signal "TOP")
		(4 "In1.Cu" signal "L2GND")
		(6 "In2.Cu" signal "L3")
		(8 "In3.Cu" signal "L4GND")
		(10 "In4.Cu" signal "L5")
		(12 "In5.Cu" signal "L6GND")
		(14 "In6.Cu" signal "L7VCC")
		(16 "In7.Cu" signal "L8VCC")
		(18 "In8.Cu" signal "L9GND")
		(20 "In9.Cu" signal "L10")
		(22 "In10.Cu" signal "L11GND")
		(24 "In11.Cu" signal "L12")
		(26 "In12.Cu" signal "L13GND")
		(2 "B.Cu" signal "BOTTOM")
		(9 "F.Adhes" user "F.Adhesive")
		(11 "B.Adhes" user "B.Adhesive")
		(13 "F.Paste" user "Package Geometry/Pastemask Top")
		(15 "B.Paste" user "Package Geometry/Pastemask Bottom")
		(5 "F.SilkS" user "Ref Des/Silkscreen Top")
		(7 "B.SilkS" user "Ref Des/Silkscreen Bottom")
		(1 "F.Mask" user "Board Geometry/Soldermask Top")
		(3 "B.Mask" user "Board Geometry/Soldermask Bottom")
		(17 "Dwgs.User" user "User.Drawings")
		(19 "Cmts.User" user "User.Comments")
		(21 "Eco1.User" user "User.Eco1")
		(23 "Eco2.User" user "User.Eco2")
		(25 "Edge.Cuts" user "Board Geometry/Outline")
		(27 "Margin" user)
		(31 "F.CrtYd" user "Package Geometry/Place Bound Top")
		(29 "B.CrtYd" user "Package Geometry/Place Bound Bottom")
		(35 "F.Fab" user "Ref Des/Assembly Top")
		(33 "B.Fab" user "Ref Des/Assembly Bottom")
	)
	(footprint ""
		(layer "F.Cu")
		(at 324.5485 -123.825 90)
		(property "Reference" "C6B6"
			(at -0.8382 -0.67818 90)
			(unlocked yes)
			(layer "F.SilkS")
			(effects
				(font
					(size 0.4064 0.254)
					(thickness 0.1524)
				)
				(justify left)
			)
		)
		(property "Value" ""
			(at 0 0 90)
			(layer "F.Fab")
			(effects
				(font
					(size 1.27 1.27)
				)
			)
		)
		(duplicate_pad_numbers_are_jumpers no)
		(fp_poly
			(pts
				(xy 0.3048 -0.1016) (xy 0.3048 0.9906) (xy -0.3048 0.9906) (xy -0.3048 -0.1016)
			)
			(stroke
				(width 0)
				(type default)
			)
			(fill no)
			(layer "F.CrtYd")
		)
		(fp_line
			(start 0.3048 -0.1016)
			(end -0.3048 -0.1016)
			(stroke
				(width 0.1)
				(type default)
			)
			(layer "F.Fab")
		)
		(fp_line
			(start -0.3048 -0.1016)
			(end -0.3048 0.9906)
			(stroke
				(width 0.1)
				(type default)
			)
			(layer "F.Fab")
		)
		(fp_line
			(start 0.3048 0.9906)
			(end 0.3048 -0.1016)
			(stroke
				(width 0.1)
				(type default)
			)
			(layer "F.Fab")
		)
		(fp_line
			(start -0.3048 0.9906)
			(end 0.3048 0.9906)
			(stroke
				(width 0.1)
				(type default)
			)
			(layer "F.Fab")
		)
		(pad "1" smd rect
			(at 0 0 90)
			(size 0.508 0.508)
			(layers "F.Cu" "F.Mask" "F.Paste")
			(net "P3E_CPU0_PE1_PCH_TXN<14>")
		)
		(pad "2" smd rect
			(at 0 0.889 90)
			(size 0.508 0.508)
			(layers "F.Cu" "F.Mask" "F.Paste")
			(net "P3E_CPU0_PE1_PCH_C_TXN<14>")
		)
		(zone
			(layer "F.Cu")
			(hatch none 0.5)
			(connect_pads
				(clearance 0)
			)
			(min_thickness 0.25)
			(keepout
				(tracks allowed)
				(vias not_allowed)
				(pads allowed)
				(copperpour not_allowed)
				(footprints allowed)
			)
			(placement
				(enabled no)
				(sheetname "")
			)
			(fill
				(thermal_gap 0.5)
				(thermal_bridge_width 0.5)
				(island_removal_mode 0)
			)
			(polygon
				(pts
					(xy 324.8025 -123.571) (xy 324.8025 -124.079) (xy 325.1835 -124.079) (xy 325.1835 -123.571)
				)
			)
		)
		(zone
			(layer "F.Cu")
			(hatch none 0.5)
			(connect_pads
				(clearance 0)
			)
			(min_thickness 0.25)
			(keepout
				(tracks not_allowed)
				(vias allowed)
				(pads allowed)
				(copperpour not_allowed)
				(footprints allowed)
			)
			(placement
				(enabled no)
				(sheetname "")
			)
			(fill
				(thermal_gap 0.5)
				(thermal_bridge_width 0.5)
				(island_removal_mode 0)
			)
			(polygon
				(pts
					(xy 325.1835 -123.571) (xy 325.1835 -124.079) (xy 324.8025 -124.079) (xy 324.8025 -123.571)
				)
			)
		)
	)
	(footprint ""
		(layer "F.Cu")
		(at 491.423706 -151.39416 -90)
		(property "Reference" "R6W19"
			(at -0.8382 -0.67818 270)
			(unlocked yes)
			(layer "F.SilkS")
			(effects
				(font
					(size 0.4064 0.254)
					(thickness 0.1524)
				)
				(justify left)
			)
		)
		(property "Value" ""
			(at 0 0 270)
			(layer "F.Fab")
			(effects
				(font
					(size 1.27 1.27)
				)
			)
		)
		(duplicate_pad_numbers_are_jumpers no)
		(fp_poly
			(pts
				(xy -0.2794 -0.1016) (xy 0.2794 -0.1016) (xy 0.2794 0.9906) (xy -0.2794 0.9906)
			)
			(stroke
				(width 0)
				(type default)
			)
			(fill no)
			(layer "F.CrtYd")
		)
		(fp_line
			(start -0.2794 0.9906)
			(end 0.2794 0.9906)
			(stroke
				(width 0.1)
				(type default)
			)
			(layer "F.Fab")
		)
		(fp_line
			(start 0.2794 0.9906)
			(end 0.2794 -0.1016)
			(stroke
				(width 0.1)
				(type default)
			)
			(layer "F.Fab")
		)
		(fp_line
			(start -0.2794 -0.1016)
			(end -0.2794 0.9906)
			(stroke
				(width 0.1)
				(type default)
			)
			(layer "F.Fab")
		)
		(fp_line
			(start 0.2794 -0.1016)
			(end -0.2794 -0.1016)
			(stroke
				(width 0.1)
				(type default)
			)
			(layer "F.Fab")
		)
		(pad "1" smd rect
			(at 0 0 270)
			(size 0.508 0.508)
			(layers "F.Cu" "F.Mask" "F.Paste")
			(net "SPA_5V_SIN_SW_D")
		)
		(pad "2" smd rect
			(at 0 0.889 270)
			(size 0.508 0.508)
			(layers "F.Cu" "F.Mask" "F.Paste")
			(net "SPA_SIN_SW_R")
		)
		(zone
			(layer "F.Cu")
			(hatch none 0.5)
			(connect_pads
				(clearance 0)
			)
			(min_thickness 0.25)
			(keepout
				(tracks not_allowed)
				(vias allowed)
				(pads allowed)
				(copperpour not_allowed)
				(footprints allowed)
			)
			(placement
				(enabled no)
				(sheetname "")
			)
			(fill
				(thermal_gap 0.5)
				(thermal_bridge_width 0.5)
				(island_removal_mode 0)
			)
			(polygon
				(pts
					(xy 490.788706 -151.64816) (xy 490.788706 -151.14016) (xy 491.169706 -151.14016) (xy 491.169706 -151.64816)
				)
			)
		)
		(zone
			(layer "F.Cu")
			(hatch none 0.5)
			(connect_pads
				(clearance 0)
			)
			(min_thickness 0.25)
			(keepout
				(tracks allowed)
				(vias not_allowed)
				(pads allowed)
				(copperpour not_allowed)
				(footprints allowed)
			)
			(placement
				(enabled no)
				(sheetname "")
			)
			(fill
				(thermal_gap 0.5)
				(thermal_bridge_width 0.5)
				(island_removal_mode 0)
			)
			(polygon
				(pts
					(xy 491.169706 -151.64816) (xy 491.169706 -151.14016) (xy 490.788706 -151.14016) (xy 490.788706 -151.64816)
				)
			)
		)
	)
	(footprint ""
		(layer "F.Cu")
		(at 407.8605 -108.966 90)
		(property "Reference" "R8C11"
			(at 0 0 90)
			(layer "F.SilkS")
			(hide yes)
			(effects
				(font
					(size 1.27 1.27)
				)
			)
		)
		(property "Value" ""
			(at 0 0 90)
			(layer "F.Fab")
			(effects
				(font
					(size 1.27 1.27)
				)
			)
		)
		(duplicate_pad_numbers_are_jumpers no)
		(fp_poly
			(pts
				(xy -0.2794 -0.1016) (xy 0.2794 -0.1016) (xy 0.2794 0.9906) (xy -0.2794 0.9906)
			)
			(stroke
				(width 0)
				(type default)
			)
			(fill no)
			(layer "F.CrtYd")
		)
		(fp_line
			(start 0.2794 -0.1016)
			(end -0.2794 -0.1016)
			(stroke
				(width 0.1)
				(type default)
			)
			(layer "F.Fab")
		)
		(fp_line
			(start -0.2794 -0.1016)
			(end -0.2794 0.9906)
			(stroke
				(width 0.1)
				(type default)
			)
			(layer "F.Fab")
		)
		(fp_line
			(start 0.2794 0.9906)
			(end 0.2794 -0.1016)
			(stroke
				(width 0.1)
				(type default)
			)
			(layer "F.Fab")
		)
		(fp_line
			(start -0.2794 0.9906)
			(end 0.2794 0.9906)
			(stroke
				(width 0.1)
				(type default)
			)
			(layer "F.Fab")
		)
		(pad "1" smd rect
			(at 0 0 90)
			(size 0.508 0.508)
			(layers "F.Cu" "F.Mask" "F.Paste")
			(net "SMB_SMLINK0_STBY_LVC3_SDA_R1")
		)
		(pad "2" smd rect
			(at 0 0.889 90)
			(size 0.508 0.508)
			(layers "F.Cu" "F.Mask" "F.Paste")
			(net "SMB_SMLINK0_STBY_LVC3_SDA")
		)
		(zone
			(layer "F.Cu")
			(hatch none 0.5)
			(connect_pads
				(clearance 0)
			)
			(min_thickness 0.25)
			(keepout
				(tracks allowed)
				(vias not_allowed)
				(pads allowed)
				(copperpour not_allowed)
				(footprints allowed)
			)
			(placement
				(enabled no)
				(sheetname "")
			)
			(fill
				(thermal_gap 0.5)
				(thermal_bridge_width 0.5)
				(island_removal_mode 0)
			)
			(polygon
				(pts
					(xy 408.1145 -108.712) (xy 408.1145 -109.22) (xy 408.4955 -109.22) (xy 408.4955 -108.712)
				)
			)
		)
		(zone
			(layer "F.Cu")
			(hatch none 0.5)
			(connect_pads
				(clearance 0)
			)
			(min_thickness 0.25)
			(keepout
				(tracks not_allowed)
				(vias allowed)
				(pads allowed)
				(copperpour not_allowed)
				(footprints allowed)
			)
			(placement
				(enabled no)
				(sheetname "")
			)
			(fill
				(thermal_gap 0.5)
				(thermal_bridge_width 0.5)
				(island_removal_mode 0)
			)
			(polygon
				(pts
					(xy 408.4955 -108.712) (xy 408.4955 -109.22) (xy 408.1145 -109.22) (xy 408.1145 -108.712)
				)
			)
		)
	)
)
